# SCM (Grand Teton) — schematic netlist excerpt (pin names and nets, part order shuffled) for the footprints in the layout excerpt that follows; sources: Cadence DE-HDL packaged netlist, KiCad conversion of 12092022_DA0F0TMDCD0_F0T_Management_Board_D_brd_V3_OCP.brd

PU1  MPQ8626GDZ  MPQ8626GD-Z IC  pkg QFN14_0-5_3X2XA  page 52
  PGND1  = GND
  SW1  = SW_P3V3_AUX_SW
  VIN  = SW_P3V3_AUX_FLT
  CS  = P3V3_AUX_CS
  EN  = PWRGD_EN_P3V3_R
  FB  = P3V3_AUX_FB_RC
  AGND  = GND
  TRK_REF  = P3V3_AUX_REF
  PGOOD  = PWRGD_P3V3_AUX_R
  BST  = SW_P3V3_AUX_BST_R
  SW2  = SW_P3V3_AUX_SW
  MODE  = P3V3_AUX_MODE
  VCC  = P3V3_AUX_VCC
  PGND2  = GND

J1  SCONN3_212H9103GBR1  SCONN3_212-H91-03GBR1 IO  pkg HEADER1X3SXE_H367  page 25
  \1\  = PU_J1_P1
  \2\  = FLASH_LATCH_Q_N_R2
  \3\  = NC_J1_P3

(kicad_pcb
	(version 20260206)
	(generator "pcbnew")
	(generator_version "10.0")
	(general
		(thickness 1.6)
		(legacy_teardrops no)
	)
	(paper "A4")
	(title_block
		(title "12092022_DA0F0TMDCD0_F0T_Management_Board_D_brd_V3_OCP.brd")
		(comment 1 "Grand Teton / footprints 420-421 of 1440")
	)
	(layers
		(0 "F.Cu" signal "TOP")
		(4 "In1.Cu" signal "GND")
		(6 "In2.Cu" signal "IN1")
		(8 "In3.Cu" signal "GND1")
		(10 "In4.Cu" signal "IN2")
		(12 "In5.Cu" signal "VCC")
		(14 "In6.Cu" signal "VCC1")
		(16 "In7.Cu" signal "IN3")
		(18 "In8.Cu" signal "GND2")
		(20 "In9.Cu" signal "IN4")
		(22 "In10.Cu" signal "GND3")
		(2 "B.Cu" signal "BOTTOM")
		(9 "F.Adhes" user "F.Adhesive")
		(11 "B.Adhes" user "B.Adhesive")
		(13 "F.Paste" user "Package Geometry/Pastemask Top")
		(15 "B.Paste" user "Package Geometry/Pastemask Bottom")
		(5 "F.SilkS" user "Ref Des/Silkscreen Top")
		(7 "B.SilkS" user "Ref Des/Silkscreen Bottom")
		(1 "F.Mask" user "Board Geometry/Soldermask Top")
		(3 "B.Mask" user "Board Geometry/Soldermask Bottom")
		(17 "Dwgs.User" user "User.Drawings")
		(19 "Cmts.User" user "User.Comments")
		(21 "Eco1.User" user "User.Eco1")
		(23 "Eco2.User" user "User.Eco2")
		(25 "Edge.Cuts" user "Board Geometry/Outline")
		(27 "Margin" user)
		(31 "F.CrtYd" user "Package Geometry/Place Bound Top")
		(29 "B.CrtYd" user "Package Geometry/Place Bound Bottom")
		(35 "F.Fab" user "Ref Des/Assembly Top")
		(33 "B.Fab" user "Ref Des/Assembly Bottom")
	)
	(footprint ""
		(layer "F.Cu")
		(at 7.79907 -64.787018 90)
		(property "Reference" "PU1"
			(at 3.716782 3.4544 90)
			(unlocked yes)
			(layer "F.SilkS")
			(effects
				(font
					(size 0.7874 0.5842)
					(thickness 0.1524)
				)
				(justify left)
			)
		)
		(property "Value" ""
			(at 0 0 90)
			(layer "F.Fab")
			(effects
				(font
					(size 1.27 1.27)
				)
			)
		)
		(duplicate_pad_numbers_are_jumpers no)
		(fp_line
			(start 1.050036 -1.549908)
			(end 1.050036 -1.253998)
			(stroke
				(width 0.1524)
				(type default)
			)
			(layer "F.SilkS")
		)
		(fp_line
			(start 0.503936 -1.549908)
			(end 1.050036 -1.549908)
			(stroke
				(width 0.1524)
				(type default)
			)
			(layer "F.SilkS")
		)
		(fp_line
			(start -1.050036 -1.549908)
			(end -0.503936 -1.549908)
			(stroke
				(width 0.1524)
				(type default)
			)
			(layer "F.SilkS")
		)
		(fp_line
			(start -1.050036 -1.253998)
			(end -1.050036 -1.549908)
			(stroke
				(width 0.1524)
				(type default)
			)
			(layer "F.SilkS")
		)
		(fp_line
			(start 1.050036 1.253998)
			(end 1.050036 1.549908)
			(stroke
				(width 0.1524)
				(type default)
			)
			(layer "F.SilkS")
		)
		(fp_line
			(start 1.050036 1.549908)
			(end 0.503936 1.549908)
			(stroke
				(width 0.1524)
				(type default)
			)
			(layer "F.SilkS")
		)
		(fp_line
			(start -0.503936 1.549908)
			(end -1.050036 1.549908)
			(stroke
				(width 0.1524)
				(type default)
			)
			(layer "F.SilkS")
		)
		(fp_line
			(start -1.050036 1.549908)
			(end -1.050036 1.253998)
			(stroke
				(width 0.1524)
				(type default)
			)
			(layer "F.SilkS")
		)
		(fp_poly
			(pts
				(xy -2.019808 -1.80086) (xy -1.341374 -2.148078) (xy -1.3335 -1.296162)
			)
			(stroke
				(width 0)
				(type default)
			)
			(fill yes)
			(layer "F.SilkS")
		)
		(fp_line
			(start 1.050036 -1.549908)
			(end 1.050036 1.549908)
			(stroke
				(width 0.1)
				(type default)
			)
			(layer "F.Fab")
		)
		(fp_line
			(start -1.050036 -1.549908)
			(end 1.050036 -1.549908)
			(stroke
				(width 0.1)
				(type default)
			)
			(layer "F.Fab")
		)
		(fp_line
			(start 1.050036 1.549908)
			(end -1.050036 1.549908)
			(stroke
				(width 0.1)
				(type default)
			)
			(layer "F.Fab")
		)
		(fp_line
			(start -1.050036 1.549908)
			(end -1.050036 -1.549908)
			(stroke
				(width 0.1)
				(type default)
			)
			(layer "F.Fab")
		)
		(fp_poly
			(pts
				(xy -2.2352 -0.618998) (xy -2.2352 -1.380998) (xy -1.4732 -0.999998)
			)
			(stroke
				(width 0)
				(type default)
			)
			(fill yes)
			(layer "F.Fab")
		)
		(pad "1" smd circle
			(at -0.94996 -0.999998)
			(size 0 0)
			(layers "F.Cu" "F.Mask" "F.Paste")
			(net "GND")
		)
		(pad "2" smd rect
			(at -0.849884 -0.499872 180)
			(size 0.254 0.9144)
			(layers "F.Cu" "F.Mask" "F.Paste")
			(net "SW_P3V3_AUX_SW")
		)
		(pad "3" smd rect
			(at -0.649986 0 180)
			(size 0.254 1.3208)
			(layers "F.Cu" "F.Mask" "F.Paste")
			(net "SW_P3V3_AUX_FLT")
		)
		(pad "4" smd rect
			(at -0.849884 0.499872 180)
			(size 0.254 0.9144)
			(layers "F.Cu" "F.Mask" "F.Paste")
			(net "P3V3_AUX_CS")
		)
		(pad "5" smd circle
			(at -0.94996 0.999998)
			(size 0 0)
			(layers "F.Cu" "F.Mask" "F.Paste")
			(net "PWRGD_EN_P3V3_R")
		)
		(pad "6" smd circle
			(at -0.249936 1.450086 90)
			(size 0 0)
			(layers "F.Cu" "F.Mask" "F.Paste")
			(net "P3V3_AUX_FB_RC")
		)
		(pad "7" smd circle
			(at 0.249936 1.450086 90)
			(size 0 0)
			(layers "F.Cu" "F.Mask" "F.Paste")
			(net "GND")
		)
		(pad "8" smd circle
			(at 0.94996 0.999998 180)
			(size 0 0)
			(layers "F.Cu" "F.Mask" "F.Paste")
			(net "P3V3_AUX_REF")
		)
		(pad "9" smd rect
			(at 0.849884 0.499872 180)
			(size 0.254 0.9144)
			(layers "F.Cu" "F.Mask" "F.Paste")
			(net "PWRGD_P3V3_AUX_R")
		)
		(pad "10" smd rect
			(at 0.849884 0 180)
			(size 0.254 0.9144)
			(layers "F.Cu" "F.Mask" "F.Paste")
			(net "SW_P3V3_AUX_BST_R")
		)
		(pad "11" smd rect
			(at 0.849884 -0.499872 180)
			(size 0.254 0.9144)
			(layers "F.Cu" "F.Mask" "F.Paste")
			(net "SW_P3V3_AUX_SW")
		)
		(pad "12" smd circle
			(at 0.94996 -0.999998 180)
			(size 0 0)
			(layers "F.Cu" "F.Mask" "F.Paste")
			(net "P3V3_AUX_MODE")
		)
		(pad "13" smd circle
			(at 0.249936 -1.450086 270)
			(size 0 0)
			(layers "F.Cu" "F.Mask" "F.Paste")
			(net "P3V3_AUX_VCC")
		)
		(pad "14" smd circle
			(at -0.249936 -1.450086 270)
			(size 0 0)
			(layers "F.Cu" "F.Mask" "F.Paste")
			(net "GND")
		)
	)
	(footprint ""
		(layer "F.Cu")
		(at 51.562 -85.9028 180)
		(property "Reference" "J1"
			(at 3.6322 -1.44907 0)
			(unlocked yes)
			(layer "F.SilkS")
			(effects
				(font
					(size 0.7874 0.5842)
					(thickness 0.1524)
				)
				(justify left)
			)
		)
		(property "Value" ""
			(at 0 0 180)
			(layer "F.Fab")
			(effects
				(font
					(size 1.27 1.27)
				)
			)
		)
		(duplicate_pad_numbers_are_jumpers no)
		(fp_line
			(start 1.249934 3.860038)
			(end 1.249934 0.6477)
			(stroke
				(width 0.1524)
				(type default)
			)
			(layer "F.SilkS")
		)
		(fp_line
			(start 1.249934 -0.6477)
			(end 1.249934 -3.860038)
			(stroke
				(width 0.1524)
				(type default)
			)
			(layer "F.SilkS")
		)
		(fp_line
			(start 1.249934 -3.860038)
			(end -1.249934 -3.860038)
			(stroke
				(width 0.1524)
				(type default)
			)
			(layer "F.SilkS")
		)
		(fp_line
			(start -1.249934 3.860038)
			(end 1.249934 3.860038)
			(stroke
				(width 0.1524)
				(type default)
			)
			(layer "F.SilkS")
		)
		(fp_line
			(start -1.249934 3.1877)
			(end -1.249934 3.860038)
			(stroke
				(width 0.1524)
				(type default)
			)
			(layer "F.SilkS")
		)
		(fp_line
			(start -1.249934 -1.8923)
			(end -1.249934 1.8923)
			(stroke
				(width 0.1524)
				(type default)
			)
			(layer "F.SilkS")
		)
		(fp_line
			(start -1.249934 -3.860038)
			(end -1.249934 -3.1877)
			(stroke
				(width 0.1524)
				(type default)
			)
			(layer "F.SilkS")
		)
		(fp_poly
			(pts
				(xy -3.7084 -3.9116) (xy -2.6924 -3.4036) (xy -3.7084 -2.8956)
			)
			(stroke
				(width 0)
				(type default)
			)
			(fill yes)
			(layer "F.SilkS")
		)
		(fp_line
			(start 1.249934 3.860038)
			(end 1.249934 -3.860038)
			(stroke
				(width 0.1)
				(type default)
			)
			(layer "F.Fab")
		)
		(fp_line
			(start 1.249934 -3.860038)
			(end -1.249934 -3.860038)
			(stroke
				(width 0.1)
				(type default)
			)
			(layer "F.Fab")
		)
		(fp_line
			(start -1.249934 3.860038)
			(end 1.249934 3.860038)
			(stroke
				(width 0.1)
				(type default)
			)
			(layer "F.Fab")
		)
		(fp_line
			(start -1.249934 -3.860038)
			(end -1.249934 3.860038)
			(stroke
				(width 0.1)
				(type default)
			)
			(layer "F.Fab")
		)
		(fp_poly
			(pts
				(xy -4.2164 -3.048) (xy -3.2004 -2.54) (xy -4.2164 -2.032)
			)
			(stroke
				(width 0)
				(type default)
			)
			(fill yes)
			(layer "F.Fab")
		)
		(pad "1" smd rect
			(at -1.374902 -2.54 90)
			(size 1.016 2.7686)
			(layers "F.Cu" "F.Mask" "F.Paste")
			(net "PU_J1_P1")
		)
		(pad "2" smd rect
			(at 1.374902 0 90)
			(size 1.016 2.7686)
			(layers "F.Cu" "F.Mask" "F.Paste")
			(net "FLASH_LATCH_Q_N_R2")
		)
		(pad "3" smd rect
			(at -1.374902 2.54 90)
			(size 1.016 2.7686)
			(layers "F.Cu" "F.Mask" "F.Paste")
			(net "NC_J1_P3")
		)
	)
)
